(kicad_pcb
	(version 20260206)
	(generator "pcbnew")
	(generator_version "10.0")
	(general
		(thickness 1.6)
		(legacy_teardrops no)
	)
	(paper "A4")
	(title_block
		(title "Bryce Canyon_IOM_IOC_16318-2_OCP.brd")
		(comment 1 "Bryce Canyon / footprints 861-868 of 1605")
	)
	(layers
		(0 "F.Cu" signal "TOP")
		(4 "In1.Cu" signal "L2GND")
		(6 "In2.Cu" signal "L3")
		(8 "In3.Cu" signal "L4VCC")
		(10 "In4.Cu" signal "L5VCC")
		(12 "In5.Cu" signal "L6")
		(14 "In6.Cu" signal "L7GND")
		(2 "B.Cu" signal "BOTTOM")
		(9 "F.Adhes" user "F.Adhesive")
		(11 "B.Adhes" user "B.Adhesive")
		(13 "F.Paste" user "Package Geometry/Pastemask Top")
		(15 "B.Paste" user "Package Geometry/Pastemask Bottom")
		(5 "F.SilkS" user "Ref Des/Silkscreen Top")
		(7 "B.SilkS" user "Ref Des/Silkscreen Bottom")
		(1 "F.Mask" user "Board Geometry/Soldermask Top")
		(3 "B.Mask" user "Board Geometry/Soldermask Bottom")
		(17 "Dwgs.User" user "User.Drawings")
		(19 "Cmts.User" user "User.Comments")
		(21 "Eco1.User" user "User.Eco1")
		(23 "Eco2.User" user "User.Eco2")
		(25 "Edge.Cuts" user "Board Geometry/Outline")
		(27 "Margin" user)
		(31 "F.CrtYd" user "Package Geometry/Place Bound Top")
		(29 "B.CrtYd" user "Package Geometry/Place Bound Bottom")
		(35 "F.Fab" user "Ref Des/Assembly Top")
		(33 "B.Fab" user "Ref Des/Assembly Bottom")
	)
	(footprint ""
		(layer "F.Cu")
		(at 84.983828 -91.750896 90)
		(property "Reference" "VIA15"
			(at 0 0 90)
			(layer "F.SilkS")
			(hide yes)
			(effects
				(font
					(size 1.27 1.27)
				)
			)
		)
		(property "Value" "85OHM-8L-1D6MM-L16L18-GP"
			(at 4.064 0.6096 90)
			(unlocked yes)
			(layer "F.Fab")
			(hide yes)
			(effects
				(font
					(size 1.016 1.016)
					(thickness 0.1524)
				)
			)
		)
		(property "Device Type" "VIA-PCIE-4P-368076"
			(at 4.064 -0.9144 90)
			(unlocked yes)
			(layer "F.Fab")
			(hide yes)
			(effects
				(font
					(size 1.016 1.016)
					(thickness 0.1524)
				)
			)
		)
		(duplicate_pad_numbers_are_jumpers no)
		(fp_rect
			(start -1.8415 0.381)
			(end 1.8415 -0.381)
			(stroke
				(width 0)
				(type default)
			)
			(fill no)
			(layer "F.CrtYd")
		)
		(fp_rect
			(start -1.8415 0.381)
			(end 1.8415 -0.381)
			(stroke
				(width 0)
				(type default)
			)
			(fill no)
			(layer "F.Fab")
		)
		(pad "1" thru_hole circle
			(at -1.4605 0 90)
			(size 0.508 0.508)
			(drill 0.254)
			(layers "*.Cu" "*.Mask")
			(remove_unused_layers no)
			(net "GND")
			(clearance 0.127)
			(thermal_gap 0.127)
		)
		(pad "2" thru_hole circle
			(at -0.4445 0 90)
			(size 0.508 0.508)
			(drill 0.254)
			(layers "*.Cu" "*.Mask")
			(remove_unused_layers no)
			(net "PCIE_IOM_TO_COMP_22_DP")
			(clearance 0.127)
			(thermal_gap 0.127)
		)
		(pad "3" thru_hole circle
			(at 0.4445 0 90)
			(size 0.508 0.508)
			(drill 0.254)
			(layers "*.Cu" "*.Mask")
			(remove_unused_layers no)
			(net "PCIE_IOM_TO_COMP_22_DN")
			(clearance 0.127)
			(thermal_gap 0.127)
		)
		(pad "4" thru_hole circle
			(at 1.4605 0 90)
			(size 0.508 0.508)
			(drill 0.254)
			(layers "*.Cu" "*.Mask")
			(remove_unused_layers no)
			(net "GND")
			(clearance 0.127)
			(thermal_gap 0.127)
		)
	)
	(footprint ""
		(layer "F.Cu")
		(at 83.316064 -138.129264 -90)
		(property "Reference" "R99"
			(at 0 0 270)
			(layer "F.SilkS")
			(hide yes)
			(effects
				(font
					(size 1.27 1.27)
				)
			)
		)
		(property "Value" "0R2J-2-GP"
			(at 0.064008 -3.993896 270)
			(unlocked yes)
			(layer "F.Fab")
			(hide yes)
			(effects
				(font
					(size 1.016 1.016)
					(thickness 0.1524)
				)
			)
		)
		(property "Device Type" "R402H16"
			(at 0.064008 -5.517896 270)
			(unlocked yes)
			(layer "F.Fab")
			(hide yes)
			(effects
				(font
					(size 1.016 1.016)
					(thickness 0.1524)
				)
			)
		)
		(duplicate_pad_numbers_are_jumpers no)
		(fp_line
			(start -0.508 -0.9398)
			(end -0.508 0.9398)
			(stroke
				(width 0.1524)
				(type default)
			)
			(layer "F.SilkS")
		)
		(fp_line
			(start 0.508 -0.9398)
			(end -0.508 -0.9398)
			(stroke
				(width 0.1524)
				(type default)
			)
			(layer "F.SilkS")
		)
		(fp_rect
			(start -0.508 0.9398)
			(end 0.508 -0.9398)
			(stroke
				(width 0)
				(type default)
			)
			(fill no)
			(layer "F.CrtYd")
		)
		(fp_rect
			(start -0.508 0.9398)
			(end 0.508 -0.9398)
			(stroke
				(width 0)
				(type default)
			)
			(fill no)
			(layer "F.Fab")
		)
		(pad "1" smd custom
			(at 0 -0.4445 270)
			(size 0.1397 0.1397)
			(layers "F.Cu" "F.Mask" "F.Paste")
			(net "P3V3_STBY")
			(options
				(clearance outline)
				(anchor circle)
			)
			(primitives
				(gr_poly
					(pts
						(arc
							(start -0.1778 -0.2794)
							(mid -0.249642 -0.249642)
							(end -0.2794 -0.1778)
						)
						(arc
							(start -0.2794 0.1778)
							(mid -0.249642 0.249642)
							(end -0.1778 0.2794)
						)
						(arc
							(start 0.1778 0.2794)
							(mid 0.249642 0.249642)
							(end 0.2794 0.1778)
						)
						(arc
							(start 0.2794 -0.1778)
							(mid 0.249642 -0.249642)
							(end 0.1778 -0.2794)
						)
					)
					(width 0)
					(fill yes)
				)
			)
		)
		(pad "2" smd custom
			(at 0 0.4445 270)
			(size 0.1397 0.1397)
			(layers "F.Cu" "F.Mask" "F.Paste")
			(net "D_FLIP_PRE#")
			(options
				(clearance outline)
				(anchor circle)
			)
			(primitives
				(gr_poly
					(pts
						(arc
							(start -0.1778 -0.2794)
							(mid -0.249642 -0.249642)
							(end -0.2794 -0.1778)
						)
						(arc
							(start -0.2794 0.1778)
							(mid -0.249642 0.249642)
							(end -0.1778 0.2794)
						)
						(arc
							(start 0.1778 0.2794)
							(mid 0.249642 0.249642)
							(end 0.2794 0.1778)
						)
						(arc
							(start 0.2794 -0.1778)
							(mid 0.249642 -0.249642)
							(end 0.1778 -0.2794)
						)
					)
					(width 0)
					(fill yes)
				)
			)
		)
	)
	(footprint ""
		(layer "F.Cu")
		(at 87.357966 -49.194212 90)
		(property "Reference" "R503"
			(at 0 0 90)
			(layer "F.SilkS")
			(hide yes)
			(effects
				(font
					(size 1.27 1.27)
				)
			)
		)
		(property "Value" "1KR2F-3-GP"
			(at 0.064008 -3.993896 90)
			(unlocked yes)
			(layer "F.Fab")
			(hide yes)
			(effects
				(font
					(size 1.016 1.016)
					(thickness 0.1524)
				)
			)
		)
		(property "Device Type" "R402H16"
			(at 0.064008 -5.517896 90)
			(unlocked yes)
			(layer "F.Fab")
			(hide yes)
			(effects
				(font
					(size 1.016 1.016)
					(thickness 0.1524)
				)
			)
		)
		(duplicate_pad_numbers_are_jumpers no)
		(fp_line
			(start 0.508 -0.9398)
			(end -0.508 -0.9398)
			(stroke
				(width 0.1524)
				(type default)
			)
			(layer "F.SilkS")
		)
		(fp_line
			(start -0.508 -0.9398)
			(end -0.508 0.9398)
			(stroke
				(width 0.1524)
				(type default)
			)
			(layer "F.SilkS")
		)
		(fp_rect
			(start -0.508 0.9398)
			(end 0.508 -0.9398)
			(stroke
				(width 0)
				(type default)
			)
			(fill no)
			(layer "F.CrtYd")
		)
		(fp_rect
			(start -0.508 0.9398)
			(end 0.508 -0.9398)
			(stroke
				(width 0)
				(type default)
			)
			(fill no)
			(layer "F.Fab")
		)
		(pad "1" smd custom
			(at 0 -0.4445 90)
			(size 0.1397 0.1397)
			(layers "F.Cu" "F.Mask" "F.Paste")
			(net "P3V3")
			(options
				(clearance outline)
				(anchor circle)
			)
			(primitives
				(gr_poly
					(pts
						(arc
							(start -0.1778 -0.2794)
							(mid -0.249642 -0.249642)
							(end -0.2794 -0.1778)
						)
						(arc
							(start -0.2794 0.1778)
							(mid -0.249642 0.249642)
							(end -0.1778 0.2794)
						)
						(arc
							(start 0.1778 0.2794)
							(mid 0.249642 0.249642)
							(end 0.2794 0.1778)
						)
						(arc
							(start 0.2794 -0.1778)
							(mid 0.249642 -0.249642)
							(end 0.1778 -0.2794)
						)
					)
					(width 0)
					(fill yes)
				)
			)
		)
		(pad "2" smd custom
			(at 0 0.4445 90)
			(size 0.1397 0.1397)
			(layers "F.Cu" "F.Mask" "F.Paste")
			(net "GND")
			(options
				(clearance outline)
				(anchor circle)
			)
			(primitives
				(gr_poly
					(pts
						(arc
							(start -0.1778 -0.2794)
							(mid -0.249642 -0.249642)
							(end -0.2794 -0.1778)
						)
						(arc
							(start -0.2794 0.1778)
							(mid -0.249642 0.249642)
							(end -0.1778 0.2794)
						)
						(arc
							(start 0.1778 0.2794)
							(mid 0.249642 0.249642)
							(end 0.2794 0.1778)
						)
						(arc
							(start 0.2794 -0.1778)
							(mid 0.249642 -0.249642)
							(end 0.1778 -0.2794)
						)
					)
					(width 0)
					(fill yes)
				)
			)
		)
	)
	(footprint ""
		(layer "F.Cu")
		(at 224.259902 -58.546492 180)
		(property "Reference" "R571"
			(at 0 0 180)
			(layer "F.SilkS")
			(hide yes)
			(effects
				(font
					(size 1.27 1.27)
				)
			)
		)
		(property "Value" "0R2J-2-GP"
			(at 0.064008 -3.993896 180)
			(unlocked yes)
			(layer "F.Fab")
			(hide yes)
			(effects
				(font
					(size 1.016 1.016)
					(thickness 0.1524)
				)
			)
		)
		(property "Device Type" "R402H16"
			(at 0.064008 -5.517896 180)
			(unlocked yes)
			(layer "F.Fab")
			(hide yes)
			(effects
				(font
					(size 1.016 1.016)
					(thickness 0.1524)
				)
			)
		)
		(duplicate_pad_numbers_are_jumpers no)
		(fp_line
			(start 0.508 -0.9398)
			(end -0.508 -0.9398)
			(stroke
				(width 0.1524)
				(type default)
			)
			(layer "F.SilkS")
		)
		(fp_line
			(start -0.508 -0.9398)
			(end -0.508 0.9398)
			(stroke
				(width 0.1524)
				(type default)
			)
			(layer "F.SilkS")
		)
		(fp_rect
			(start -0.508 0.9398)
			(end 0.508 -0.9398)
			(stroke
				(width 0)
				(type default)
			)
			(fill no)
			(layer "F.CrtYd")
		)
		(fp_rect
			(start -0.508 0.9398)
			(end 0.508 -0.9398)
			(stroke
				(width 0)
				(type default)
			)
			(fill no)
			(layer "F.Fab")
		)
		(pad "1" smd custom
			(at 0 -0.4445 180)
			(size 0.1397 0.1397)
			(layers "F.Cu" "F.Mask" "F.Paste")
			(net "REF_CLK")
			(options
				(clearance outline)
				(anchor circle)
			)
			(primitives
				(gr_poly
					(pts
						(arc
							(start -0.1778 -0.2794)
							(mid -0.249642 -0.249642)
							(end -0.2794 -0.1778)
						)
						(arc
							(start -0.2794 0.1778)
							(mid -0.249642 0.249642)
							(end -0.1778 0.2794)
						)
						(arc
							(start 0.1778 0.2794)
							(mid 0.249642 0.249642)
							(end 0.2794 0.1778)
						)
						(arc
							(start 0.2794 -0.1778)
							(mid 0.249642 -0.249642)
							(end 0.1778 -0.2794)
						)
					)
					(width 0)
					(fill yes)
				)
			)
		)
		(pad "2" smd custom
			(at 0 0.4445 180)
			(size 0.1397 0.1397)
			(layers "F.Cu" "F.Mask" "F.Paste")
			(net "IOC_REF_CLK_N")
			(options
				(clearance outline)
				(anchor circle)
			)
			(primitives
				(gr_poly
					(pts
						(arc
							(start -0.1778 -0.2794)
							(mid -0.249642 -0.249642)
							(end -0.2794 -0.1778)
						)
						(arc
							(start -0.2794 0.1778)
							(mid -0.249642 0.249642)
							(end -0.1778 0.2794)
						)
						(arc
							(start 0.1778 0.2794)
							(mid 0.249642 0.249642)
							(end 0.2794 0.1778)
						)
						(arc
							(start 0.2794 -0.1778)
							(mid 0.249642 -0.249642)
							(end 0.1778 -0.2794)
						)
					)
					(width 0)
					(fill yes)
				)
			)
		)
	)
	(footprint ""
		(layer "F.Cu")
		(at 62.6872 -137.6426)
		(property "Reference" "TP55"
			(at 0 0 0)
			(layer "F.SilkS")
			(hide yes)
			(effects
				(font
					(size 1.27 1.27)
				)
			)
		)
		(property "Value" "TPAD28-2-GP"
			(at -0.0127 -1.6637 0)
			(unlocked yes)
			(layer "F.Fab")
			(hide yes)
			(effects
				(font
					(size 1.016 1.016)
					(thickness 0.1524)
				)
			)
		)
		(property "Device Type" "TPAD28"
			(at -0.0127 -3.1877 0)
			(unlocked yes)
			(layer "F.Fab")
			(hide yes)
			(effects
				(font
					(size 1.016 1.016)
					(thickness 0.1524)
				)
			)
		)
		(duplicate_pad_numbers_are_jumpers no)
		(fp_poly
			(pts
				(arc
					(start 0.3556 0)
					(mid -0.3556 0)
					(end 0.3556 0)
				)
			)
			(stroke
				(width 0)
				(type default)
			)
			(fill no)
			(layer "F.CrtYd")
		)
		(fp_poly
			(pts
				(arc
					(start 0.6096 0)
					(mid -0.6096 0)
					(end 0.6096 0)
				)
			)
			(stroke
				(width 0)
				(type default)
			)
			(fill no)
			(layer "F.Fab")
		)
		(pad "1" smd circle
			(at 0 0)
			(size 0.7112 0.7112)
			(layers "F.Cu" "F.Mask" "F.Paste")
			(net "TP_BMC_GPIOA7")
		)
	)
	(footprint ""
		(layer "F.Cu")
		(at 140.9954 -14.44752)
		(property "Reference" "U50"
			(at 0 0 0)
			(layer "F.SilkS")
			(hide yes)
			(effects
				(font
					(size 1.27 1.27)
				)
			)
		)
		(property "Value" "74LVC1G86DCKR-GP"
			(at -2.3368 -8.6868 0)
			(unlocked yes)
			(layer "F.Fab")
			(hide yes)
			(effects
				(font
					(size 1.016 1.016)
					(thickness 0.1524)
				)
			)
		)
		(property "Device Type" "SC70-5H44"
			(at -2.3114 -10.414 0)
			(unlocked yes)
			(layer "F.Fab")
			(hide yes)
			(effects
				(font
					(size 1.016 1.016)
					(thickness 0.1524)
				)
			)
		)
		(duplicate_pad_numbers_are_jumpers no)
		(fp_line
			(start -1.27 -1.7018)
			(end 1.27 -1.7018)
			(stroke
				(width 0.1524)
				(type default)
			)
			(layer "F.SilkS")
		)
		(fp_line
			(start -1.27 1.7018)
			(end -1.27 -1.7018)
			(stroke
				(width 0.1524)
				(type default)
			)
			(layer "F.SilkS")
		)
		(fp_line
			(start 0.6604 -1.8034)
			(end 1.3843 -1.8034)
			(stroke
				(width 0.3302)
				(type default)
			)
			(layer "F.SilkS")
		)
		(fp_line
			(start 1.27 -1.7018)
			(end 1.27 1.7018)
			(stroke
				(width 0.1524)
				(type default)
			)
			(layer "F.SilkS")
		)
		(fp_line
			(start 1.27 1.7018)
			(end -1.27 1.7018)
			(stroke
				(width 0.1524)
				(type default)
			)
			(layer "F.SilkS")
		)
		(fp_line
			(start 1.3843 -1.8034)
			(end 1.3843 -1.1176)
			(stroke
				(width 0.3302)
				(type default)
			)
			(layer "F.SilkS")
		)
		(fp_rect
			(start -1.524 1.9558)
			(end 1.524 -1.9558)
			(stroke
				(width 0)
				(type default)
			)
			(fill no)
			(layer "F.CrtYd")
		)
		(fp_poly
			(pts
				(xy -1.524 -1.9558) (xy 1.524 -1.9558) (xy 1.524 1.9558) (xy -1.524 1.9558)
			)
			(stroke
				(width 0)
				(type default)
			)
			(fill no)
			(layer "F.Fab")
		)
		(pad "1" smd rect
			(at 0.65024 -0.8255)
			(size 0.4064 1.2192)
			(layers "F.Cu" "F.Mask" "F.Paste")
			(net "IOC_EXT2_LED_B")
		)
		(pad "2" smd rect
			(at 0 -0.8255)
			(size 0.4064 1.2192)
			(layers "F.Cu" "F.Mask" "F.Paste")
			(net "IOC_EXT2_LED_Y")
		)
		(pad "3" smd rect
			(at -0.65024 -0.8255)
			(size 0.4064 1.2192)
			(layers "F.Cu" "F.Mask" "F.Paste")
			(net "GND")
		)
		(pad "4" smd rect
			(at -0.65024 0.8255)
			(size 0.4064 1.2192)
			(layers "F.Cu" "F.Mask" "F.Paste")
			(net "IOC_EXT2_LED_Y_XOR")
		)
		(pad "5" smd rect
			(at 0.65024 0.8255)
			(size 0.4064 1.2192)
			(layers "F.Cu" "F.Mask" "F.Paste")
			(net "P1V8")
		)
	)
	(footprint ""
		(layer "F.Cu")
		(at 91.6432 -125.349 180)
		(property "Reference" "C522"
			(at 0 0 180)
			(layer "F.SilkS")
			(hide yes)
			(effects
				(font
					(size 1.27 1.27)
				)
			)
		)
		(property "Value" "SCD1U25V2KX-2-GP"
			(at 1.1811 -2.7051 180)
			(unlocked yes)
			(layer "F.Fab")
			(hide yes)
			(effects
				(font
					(size 1.016 1.016)
					(thickness 0.1524)
				)
			)
		)
		(property "Device Type" "C402H22"
			(at 1.1811 -4.2291 180)
			(unlocked yes)
			(layer "F.Fab")
			(hide yes)
			(effects
				(font
					(size 1.016 1.016)
					(thickness 0.1524)
				)
			)
		)
		(duplicate_pad_numbers_are_jumpers no)
		(fp_rect
			(start -0.4318 0.9525)
			(end 0.4318 -0.9525)
			(stroke
				(width 0)
				(type default)
			)
			(fill no)
			(layer "F.CrtYd")
		)
		(fp_rect
			(start -0.4318 0.9525)
			(end 0.4318 -0.9525)
			(stroke
				(width 0)
				(type default)
			)
			(fill no)
			(layer "F.Fab")
		)
		(pad "1" smd custom
			(at 0 -0.4445 180)
			(size 0.1524 0.1524)
			(layers "F.Cu" "F.Mask" "F.Paste")
			(net "P3V3_STBY")
			(options
				(clearance outline)
				(anchor circle)
			)
			(primitives
				(gr_poly
					(pts
						(arc
							(start 0.3048 -0.2032)
							(mid 0.275042 -0.275042)
							(end 0.2032 -0.3048)
						)
						(arc
							(start -0.2032 -0.3048)
							(mid -0.275042 -0.275042)
							(end -0.3048 -0.2032)
						)
						(arc
							(start -0.3048 0.2032)
							(mid -0.275042 0.275042)
							(end -0.2032 0.3048)
						)
						(arc
							(start 0.2032 0.3048)
							(mid 0.275042 0.275042)
							(end 0.3048 0.2032)
						)
					)
					(width 0)
					(fill yes)
				)
			)
		)
		(pad "2" smd custom
			(at 0 0.4445 180)
			(size 0.1524 0.1524)
			(layers "F.Cu" "F.Mask" "F.Paste")
			(net "GND")
			(options
				(clearance outline)
				(anchor circle)
			)
			(primitives
				(gr_poly
					(pts
						(arc
							(start 0.3048 -0.2032)
							(mid 0.275042 -0.275042)
							(end 0.2032 -0.3048)
						)
						(arc
							(start -0.2032 -0.3048)
							(mid -0.275042 -0.275042)
							(end -0.3048 -0.2032)
						)
						(arc
							(start -0.3048 0.2032)
							(mid -0.275042 0.275042)
							(end -0.2032 0.3048)
						)
						(arc
							(start 0.2032 0.3048)
							(mid 0.275042 0.275042)
							(end 0.3048 0.2032)
						)
					)
					(width 0)
					(fill yes)
				)
			)
		)
	)
	(footprint ""
		(layer "F.Cu")
		(at 165.0238 -126.8984 90)
		(property "Reference" "C211"
			(at 0 0 90)
			(layer "F.SilkS")
			(hide yes)
			(effects
				(font
					(size 1.27 1.27)
				)
			)
		)
		(property "Value" "SCD1U50V3KX-GP"
			(at 0 -2.8194 90)
			(unlocked yes)
			(layer "F.Fab")
			(hide yes)
			(effects
				(font
					(size 1.016 1.016)
					(thickness 0.1524)
				)
			)
		)
		(property "Device Type" "C603H36"
			(at 0 -4.3434 90)
			(unlocked yes)
			(layer "F.Fab")
			(hide yes)
			(effects
				(font
					(size 1.016 1.016)
					(thickness 0.1524)
				)
			)
		)
		(duplicate_pad_numbers_are_jumpers no)
		(fp_line
			(start 0.508 0)
			(end -0.508 0)
			(stroke
				(width 0.2032)
				(type default)
			)
			(layer "F.SilkS")
		)
		(fp_rect
			(start -0.5842 1.3335)
			(end 0.5842 -1.3335)
			(stroke
				(width 0)
				(type default)
			)
			(fill no)
			(layer "F.CrtYd")
		)
		(fp_rect
			(start -0.5842 1.3335)
			(end 0.5842 -1.3335)
			(stroke
				(width 0)
				(type default)
			)
			(fill no)
			(layer "F.Fab")
		)
		(pad "1" smd custom
			(at 0 -0.762 90)
			(size 0.2159 0.2159)
			(layers "F.Cu" "F.Mask" "F.Paste")
			(net "P1V8_STBY")
			(options
				(clearance outline)
				(anchor circle)
			)
			(primitives
				(gr_poly
					(pts
						(arc
							(start -0.3302 -0.4318)
							(mid -0.402042 -0.402042)
							(end -0.4318 -0.3302)
						)
						(arc
							(start -0.4318 0.3302)
							(mid -0.402042 0.402042)
							(end -0.3302 0.4318)
						)
						(arc
							(start 0.3302 0.4318)
							(mid 0.402042 0.402042)
							(end 0.4318 0.3302)
						)
						(arc
							(start 0.4318 -0.3302)
							(mid 0.402042 -0.402042)
							(end 0.3302 -0.4318)
						)
					)
					(width 0)
					(fill yes)
				)
			)
		)
		(pad "2" smd custom
			(at 0 0.762 90)
			(size 0.2159 0.2159)
			(layers "F.Cu" "F.Mask" "F.Paste")
			(net "P1V8_STBY_VFB_R")
			(options
				(clearance outline)
				(anchor circle)
			)
			(primitives
				(gr_poly
					(pts
						(arc
							(start -0.3302 -0.4318)
							(mid -0.402042 -0.402042)
							(end -0.4318 -0.3302)
						)
						(arc
							(start -0.4318 0.3302)
							(mid -0.402042 0.402042)
							(end -0.3302 0.4318)
						)
						(arc
							(start 0.3302 0.4318)
							(mid 0.402042 0.402042)
							(end 0.4318 0.3302)
						)
						(arc
							(start 0.4318 -0.3302)
							(mid 0.402042 -0.402042)
							(end 0.3302 -0.4318)
						)
					)
					(width 0)
					(fill yes)
				)
			)
		)
	)
)
